# T6G (Grand Teton) — schematic netlist excerpt (pin names and nets, part order shuffled) for the footprints in the layout excerpt that follows; sources: Cadence DE-HDL packaged netlist, KiCad conversion of 04192023_DAF0TMB3IC0_F0TG_MB_C_brd_V02_OCP.brd

R6857  Q_RES  33 5% CHIP  pkg 0402LF  page 151 : A = SMB_SCM_2_R6_SDA ; B = P0V9_RETIMER_CPU0_PMSDA
R52  Q_RES  10K 1% EMPTY  pkg 0402LF  page 238 : A = P3V3_AUX ; B = CPU_FRU_ADDR2

(kicad_pcb
	(version 20260206)
	(generator "pcbnew")
	(generator_version "10.0")
	(general
		(thickness 1.6)
		(legacy_teardrops no)
	)
	(paper "A4")
	(title_block
		(title "04192023_DAF0TMB3IC0_F0TG_MB_C_brd_V02_OCP.brd")
		(comment 1 "Grand Teton / footprints 2544-2545 of 8354")
	)
	(layers
		(0 "F.Cu" signal "TOP")
		(4 "In1.Cu" signal "GND")
		(6 "In2.Cu" signal "IN1")
		(8 "In3.Cu" signal "GND1")
		(10 "In4.Cu" signal "IN2")
		(12 "In5.Cu" signal "GND2")
		(14 "In6.Cu" signal "IN3")
		(16 "In7.Cu" signal "GND3")
		(18 "In8.Cu" signal "VCC")
		(20 "In9.Cu" signal "VCC1")
		(22 "In10.Cu" signal "GND4")
		(24 "In11.Cu" signal "IN4")
		(26 "In12.Cu" signal "GND5")
		(28 "In13.Cu" signal "IN5")
		(30 "In14.Cu" signal "GND6")
		(32 "In15.Cu" signal "IN6")
		(34 "In16.Cu" signal "GND7")
		(2 "B.Cu" signal "BOTTOM")
		(9 "F.Adhes" user "F.Adhesive")
		(11 "B.Adhes" user "B.Adhesive")
		(13 "F.Paste" user "Package Geometry/Pastemask Top")
		(15 "B.Paste" user "Package Geometry/Pastemask Bottom")
		(5 "F.SilkS" user "Ref Des/Silkscreen Top")
		(7 "B.SilkS" user "Ref Des/Silkscreen Bottom")
		(1 "F.Mask" user "Board Geometry/Soldermask Top")
		(3 "B.Mask" user "Board Geometry/Soldermask Bottom")
		(17 "Dwgs.User" user "User.Drawings")
		(19 "Cmts.User" user "User.Comments")
		(21 "Eco1.User" user "User.Eco1")
		(23 "Eco2.User" user "User.Eco2")
		(25 "Edge.Cuts" user "Board Geometry/Outline")
		(27 "Margin" user)
		(31 "F.CrtYd" user "Package Geometry/Place Bound Top")
		(29 "B.CrtYd" user "Package Geometry/Place Bound Bottom")
		(35 "F.Fab" user "Ref Des/Assembly Top")
		(33 "B.Fab" user "Ref Des/Assembly Bottom")
	)
	(footprint ""
		(layer "F.Cu")
		(at 421.104568 -369.28044 90)
		(property "Reference" "R6857"
			(at 0 0 90)
			(layer "F.SilkS")
			(hide yes)
			(effects
				(font
					(size 1.27 1.27)
				)
			)
		)
		(property "Value" ""
			(at 0 0 90)
			(layer "F.Fab")
			(effects
				(font
					(size 1.27 1.27)
				)
			)
		)
		(duplicate_pad_numbers_are_jumpers no)
		(fp_line
			(start 0.7874 -0.4064)
			(end 0.7874 0.4064)
			(stroke
				(width 0.1524)
				(type default)
			)
			(layer "F.SilkS")
		)
		(fp_line
			(start -0.7874 -0.4064)
			(end 0.7874 -0.4064)
			(stroke
				(width 0.1524)
				(type default)
			)
			(layer "F.SilkS")
		)
		(fp_line
			(start 0.7874 0.4064)
			(end -0.7874 0.4064)
			(stroke
				(width 0.1524)
				(type default)
			)
			(layer "F.SilkS")
		)
		(fp_line
			(start -0.7874 0.4064)
			(end -0.7874 -0.4064)
			(stroke
				(width 0.1524)
				(type default)
			)
			(layer "F.SilkS")
		)
		(fp_line
			(start -0.12065 -0.305054)
			(end -0.12065 -0.2794)
			(stroke
				(width 0.1)
				(type default)
			)
			(layer "F.Fab")
		)
		(fp_line
			(start -0.67945 -0.305054)
			(end -0.12065 -0.305054)
			(stroke
				(width 0.1)
				(type default)
			)
			(layer "F.Fab")
		)
		(fp_line
			(start 0.67945 -0.3048)
			(end 0.67945 0.3048)
			(stroke
				(width 0.1)
				(type default)
			)
			(layer "F.Fab")
		)
		(fp_line
			(start 0.12065 -0.3048)
			(end 0.67945 -0.3048)
			(stroke
				(width 0.1)
				(type default)
			)
			(layer "F.Fab")
		)
		(fp_line
			(start 0.12065 -0.2794)
			(end 0.12065 -0.3048)
			(stroke
				(width 0.1)
				(type default)
			)
			(layer "F.Fab")
		)
		(fp_line
			(start -0.12065 -0.2794)
			(end 0.12065 -0.2794)
			(stroke
				(width 0.1)
				(type default)
			)
			(layer "F.Fab")
		)
		(fp_line
			(start 0.120396 0.2794)
			(end -0.12065 0.2794)
			(stroke
				(width 0.1)
				(type default)
			)
			(layer "F.Fab")
		)
		(fp_line
			(start -0.12065 0.2794)
			(end -0.12065 0.3048)
			(stroke
				(width 0.1)
				(type default)
			)
			(layer "F.Fab")
		)
		(fp_line
			(start 0.67945 0.3048)
			(end 0.120396 0.3048)
			(stroke
				(width 0.1)
				(type default)
			)
			(layer "F.Fab")
		)
		(fp_line
			(start 0.120396 0.3048)
			(end 0.120396 0.2794)
			(stroke
				(width 0.1)
				(type default)
			)
			(layer "F.Fab")
		)
		(fp_line
			(start -0.12065 0.3048)
			(end -0.67945 0.3048)
			(stroke
				(width 0.1)
				(type default)
			)
			(layer "F.Fab")
		)
		(fp_line
			(start -0.67945 0.3048)
			(end -0.67945 -0.305054)
			(stroke
				(width 0.1)
				(type default)
			)
			(layer "F.Fab")
		)
		(pad "1" smd circle
			(at -0.40005 0 90)
			(size 0 0)
			(layers "F.Cu" "F.Mask" "F.Paste")
			(net "SMB_SCM_2_R6_SDA")
		)
		(pad "2" smd circle
			(at 0.40005 0 90)
			(size 0 0)
			(layers "F.Cu" "F.Mask" "F.Paste")
			(net "P0V9_RETIMER_CPU0_PMSDA")
		)
	)
	(footprint ""
		(layer "F.Cu")
		(at 302.241458 -110.795308)
		(property "Reference" "R52"
			(at 0 0 0)
			(layer "F.SilkS")
			(hide yes)
			(effects
				(font
					(size 1.27 1.27)
				)
			)
		)
		(property "Value" ""
			(at 0 0 0)
			(layer "F.Fab")
			(effects
				(font
					(size 1.27 1.27)
				)
			)
		)
		(duplicate_pad_numbers_are_jumpers no)
		(fp_line
			(start -0.7874 -0.4064)
			(end 0.7874 -0.4064)
			(stroke
				(width 0.1524)
				(type default)
			)
			(layer "F.SilkS")
		)
		(fp_line
			(start -0.7874 0.4064)
			(end -0.7874 -0.4064)
			(stroke
				(width 0.1524)
				(type default)
			)
			(layer "F.SilkS")
		)
		(fp_line
			(start 0.7874 -0.4064)
			(end 0.7874 0.4064)
			(stroke
				(width 0.1524)
				(type default)
			)
			(layer "F.SilkS")
		)
		(fp_line
			(start 0.7874 0.4064)
			(end -0.7874 0.4064)
			(stroke
				(width 0.1524)
				(type default)
			)
			(layer "F.SilkS")
		)
		(fp_line
			(start -0.67945 -0.305054)
			(end -0.12065 -0.305054)
			(stroke
				(width 0.1)
				(type default)
			)
			(layer "F.Fab")
		)
		(fp_line
			(start -0.67945 0.3048)
			(end -0.67945 -0.305054)
			(stroke
				(width 0.1)
				(type default)
			)
			(layer "F.Fab")
		)
		(fp_line
			(start -0.12065 -0.305054)
			(end -0.12065 -0.2794)
			(stroke
				(width 0.1)
				(type default)
			)
			(layer "F.Fab")
		)
		(fp_line
			(start -0.12065 -0.2794)
			(end 0.12065 -0.2794)
			(stroke
				(width 0.1)
				(type default)
			)
			(layer "F.Fab")
		)
		(fp_line
			(start -0.12065 0.2794)
			(end -0.12065 0.3048)
			(stroke
				(width 0.1)
				(type default)
			)
			(layer "F.Fab")
		)
		(fp_line
			(start -0.12065 0.3048)
			(end -0.67945 0.3048)
			(stroke
				(width 0.1)
				(type default)
			)
			(layer "F.Fab")
		)
		(fp_line
			(start 0.120396 0.2794)
			(end -0.12065 0.2794)
			(stroke
				(width 0.1)
				(type default)
			)
			(layer "F.Fab")
		)
		(fp_line
			(start 0.120396 0.3048)
			(end 0.120396 0.2794)
			(stroke
				(width 0.1)
				(type default)
			)
			(layer "F.Fab")
		)
		(fp_line
			(start 0.12065 -0.3048)
			(end 0.67945 -0.3048)
			(stroke
				(width 0.1)
				(type default)
			)
			(layer "F.Fab")
		)
		(fp_line
			(start 0.12065 -0.2794)
			(end 0.12065 -0.3048)
			(stroke
				(width 0.1)
				(type default)
			)
			(layer "F.Fab")
		)
		(fp_line
			(start 0.67945 -0.3048)
			(end 0.67945 0.3048)
			(stroke
				(width 0.1)
				(type default)
			)
			(layer "F.Fab")
		)
		(fp_line
			(start 0.67945 0.3048)
			(end 0.120396 0.3048)
			(stroke
				(width 0.1)
				(type default)
			)
			(layer "F.Fab")
		)
		(pad "1" smd circle
			(at -0.40005 0)
			(size 0 0)
			(layers "F.Cu" "F.Mask" "F.Paste")
			(net "P3V3_AUX")
		)
		(pad "2" smd circle
			(at 0.40005 0)
			(size 0 0)
			(layers "F.Cu" "F.Mask" "F.Paste")
			(net "CPU_FRU_ADDR2")
		)
	)
)
